# S9S_MB_2U (Grand Teton) — schematic netlist excerpt (pin names and nets, part order shuffled) for the footprints in the layout excerpt that follows; sources: Cadence DE-HDL packaged netlist, KiCad conversion of 03242023_DA0F0TMBIJ0_F0T_Motherboard_J_brd_V01_OCP.brd

R4738  Q_RES  100K 1% EMPTY  pkg 0402LF  page 144 : A = PRSNT_CABLE_SWB_B1_N ; B = GND

(kicad_pcb
	(version 20260206)
	(generator "pcbnew")
	(generator_version "10.0")
	(general
		(thickness 1.6)
		(legacy_teardrops no)
	)
	(paper "A4")
	(title_block
		(title "03242023_DA0F0TMBIJ0_F0T_Motherboard_J_brd_V01_OCP.brd")
		(comment 1 "Grand Teton / footprints 1689-1689 of 6105")
	)
	(layers
		(0 "F.Cu" signal "TOP")
		(4 "In1.Cu" signal "GND")
		(6 "In2.Cu" signal "IN1")
		(8 "In3.Cu" signal "GND1")
		(10 "In4.Cu" signal "IN2")
		(12 "In5.Cu" signal "GND2")
		(14 "In6.Cu" signal "IN3")
		(16 "In7.Cu" signal "GND3")
		(18 "In8.Cu" signal "VCC")
		(20 "In9.Cu" signal "VCC1")
		(22 "In10.Cu" signal "GND4")
		(24 "In11.Cu" signal "IN4")
		(26 "In12.Cu" signal "GND5")
		(28 "In13.Cu" signal "IN5")
		(30 "In14.Cu" signal "GND6")
		(32 "In15.Cu" signal "IN6")
		(34 "In16.Cu" signal "GND7")
		(2 "B.Cu" signal "BOTTOM")
		(9 "F.Adhes" user "F.Adhesive")
		(11 "B.Adhes" user "B.Adhesive")
		(13 "F.Paste" user "Package Geometry/Pastemask Top")
		(15 "B.Paste" user "Package Geometry/Pastemask Bottom")
		(5 "F.SilkS" user "Ref Des/Silkscreen Top")
		(7 "B.SilkS" user "Ref Des/Silkscreen Bottom")
		(1 "F.Mask" user "Board Geometry/Soldermask Top")
		(3 "B.Mask" user "Board Geometry/Soldermask Bottom")
		(17 "Dwgs.User" user "User.Drawings")
		(19 "Cmts.User" user "User.Comments")
		(21 "Eco1.User" user "User.Eco1")
		(23 "Eco2.User" user "User.Eco2")
		(25 "Edge.Cuts" user "Board Geometry/Outline")
		(27 "Margin" user)
		(31 "F.CrtYd" user "Package Geometry/Place Bound Top")
		(29 "B.CrtYd" user "Package Geometry/Place Bound Bottom")
		(35 "F.Fab" user "Ref Des/Assembly Top")
		(33 "B.Fab" user "Ref Des/Assembly Bottom")
	)
	(footprint ""
		(layer "F.Cu")
		(at 366.3696 -409.194 180)
		(property "Reference" "R4738"
			(at 0 0 180)
			(layer "F.SilkS")
			(hide yes)
			(effects
				(font
					(size 1.27 1.27)
				)
			)
		)
		(property "Value" ""
			(at 0 0 180)
			(layer "F.Fab")
			(effects
				(font
					(size 1.27 1.27)
				)
			)
		)
		(duplicate_pad_numbers_are_jumpers no)
		(fp_line
			(start 0.7874 0.4064)
			(end -0.7874 0.4064)
			(stroke
				(width 0.1524)
				(type default)
			)
			(layer "F.SilkS")
		)
		(fp_line
			(start 0.7874 -0.4064)
			(end 0.7874 0.4064)
			(stroke
				(width 0.1524)
				(type default)
			)
			(layer "F.SilkS")
		)
		(fp_line
			(start -0.7874 0.4064)
			(end -0.7874 -0.4064)
			(stroke
				(width 0.1524)
				(type default)
			)
			(layer "F.SilkS")
		)
		(fp_line
			(start -0.7874 -0.4064)
			(end 0.7874 -0.4064)
			(stroke
				(width 0.1524)
				(type default)
			)
			(layer "F.SilkS")
		)
		(fp_line
			(start 0.67945 0.3048)
			(end 0.120396 0.3048)
			(stroke
				(width 0.1)
				(type default)
			)
			(layer "F.Fab")
		)
		(fp_line
			(start 0.67945 -0.3048)
			(end 0.67945 0.3048)
			(stroke
				(width 0.1)
				(type default)
			)
			(layer "F.Fab")
		)
		(fp_line
			(start 0.12065 -0.2794)
			(end 0.12065 -0.3048)
			(stroke
				(width 0.1)
				(type default)
			)
			(layer "F.Fab")
		)
		(fp_line
			(start 0.12065 -0.3048)
			(end 0.67945 -0.3048)
			(stroke
				(width 0.1)
				(type default)
			)
			(layer "F.Fab")
		)
		(fp_line
			(start 0.120396 0.3048)
			(end 0.120396 0.2794)
			(stroke
				(width 0.1)
				(type default)
			)
			(layer "F.Fab")
		)
		(fp_line
			(start 0.120396 0.2794)
			(end -0.12065 0.2794)
			(stroke
				(width 0.1)
				(type default)
			)
			(layer "F.Fab")
		)
		(fp_line
			(start -0.12065 0.3048)
			(end -0.67945 0.3048)
			(stroke
				(width 0.1)
				(type default)
			)
			(layer "F.Fab")
		)
		(fp_line
			(start -0.12065 0.2794)
			(end -0.12065 0.3048)
			(stroke
				(width 0.1)
				(type default)
			)
			(layer "F.Fab")
		)
		(fp_line
			(start -0.12065 -0.2794)
			(end 0.12065 -0.2794)
			(stroke
				(width 0.1)
				(type default)
			)
			(layer "F.Fab")
		)
		(fp_line
			(start -0.12065 -0.305054)
			(end -0.12065 -0.2794)
			(stroke
				(width 0.1)
				(type default)
			)
			(layer "F.Fab")
		)
		(fp_line
			(start -0.67945 0.3048)
			(end -0.67945 -0.305054)
			(stroke
				(width 0.1)
				(type default)
			)
			(layer "F.Fab")
		)
		(fp_line
			(start -0.67945 -0.305054)
			(end -0.12065 -0.305054)
			(stroke
				(width 0.1)
				(type default)
			)
			(layer "F.Fab")
		)
		(pad "1" smd circle
			(at -0.40005 0 180)
			(size 0 0)
			(layers "F.Cu" "F.Mask" "F.Paste")
			(net "PRSNT_CABLE_SWB_B1_N")
		)
		(pad "2" smd circle
			(at 0.40005 0 180)
			(size 0 0)
			(layers "F.Cu" "F.Mask" "F.Paste")
			(net "GND")
		)
	)
)
